# TIMECARD (Time Appliance Project (Time Card)) — schematic netlist excerpt (pin names and nets, part order shuffled) for the footprints in the layout excerpt that follows; sources: Cadence DE-HDL packaged netlist, KiCad conversion of R4006-B0001-02_R01.brd

R386  RESISTOR  33OHM 1%  pkg SMC_0402R_H016  page 26 : \1\ = SMA1_LED_GREEN_N ; \2\ = UNNAMED_14_LED4PV14_I265_4
R96  RESISTOR  33OHM 1%  pkg SMC_0402R_H016  page 21 : \1\ = MAC_ALARM ; \2\ = FPGA_IN_MAC_ALARM_OUT_N

(kicad_pcb
	(version 20260206)
	(generator "pcbnew")
	(generator_version "10.0")
	(general
		(thickness 1.6)
		(legacy_teardrops no)
	)
	(paper "A4")
	(title_block
		(title "timecard-production-celestica-r4006 — R4006-B0001-02_R01.brd")
		(comment 1 "Time Appliance Project (Time Card) / footprints 57-58 of 1113")
	)
	(layers
		(0 "F.Cu" signal "TOP")
		(4 "In1.Cu" signal "L02_GND1")
		(6 "In2.Cu" signal "L03_SIG1")
		(8 "In3.Cu" signal "L04_GND2")
		(10 "In4.Cu" signal "L05_VCC1")
		(12 "In5.Cu" signal "L06_VCC2")
		(14 "In6.Cu" signal "L07_GND3")
		(16 "In7.Cu" signal "L08_SIG2")
		(18 "In8.Cu" signal "L09_GND4")
		(2 "B.Cu" signal "BOTTOM")
		(9 "F.Adhes" user "F.Adhesive")
		(11 "B.Adhes" user "B.Adhesive")
		(13 "F.Paste" user "Package Geometry/Pastemask Top")
		(15 "B.Paste" user "Package Geometry/Pastemask Bottom")
		(5 "F.SilkS" user "Ref Des/Silkscreen Top")
		(7 "B.SilkS" user "Ref Des/Silkscreen Bottom")
		(1 "F.Mask" user "Board Geometry/Soldermask Top")
		(3 "B.Mask" user "Board Geometry/Soldermask Bottom")
		(17 "Dwgs.User" user "User.Drawings")
		(19 "Cmts.User" user "User.Comments")
		(21 "Eco1.User" user "User.Eco1")
		(23 "Eco2.User" user "User.Eco2")
		(25 "Edge.Cuts" user "Board Geometry/Outline")
		(27 "Margin" user)
		(31 "F.CrtYd" user "Package Geometry/Place Bound Top")
		(29 "B.CrtYd" user "Package Geometry/Place Bound Bottom")
		(35 "F.Fab" user "Ref Des/Assembly Top")
		(33 "B.Fab" user "Ref Des/Assembly Bottom")
	)
	(footprint ""
		(layer "F.Cu")
		(at 10.5664 -39.318692 90)
		(property "Reference" "R386"
			(at 0.178308 1.02235 90)
			(unlocked yes)
			(layer "F.SilkS")
			(effects
				(font
					(size 0.635 0.4064)
					(thickness 0.1524)
				)
			)
		)
		(property "Value" "VAL*"
			(at 0.02032 2.13233 90)
			(unlocked yes)
			(layer "F.Fab")
			(hide yes)
			(effects
				(font
					(size 0.7874 0.5842)
					(thickness 0.1524)
				)
			)
		)
		(property "Tolerance" "TOL*"
			(at 0.044704 3.05435 90)
			(unlocked yes)
			(layer "Cmts.User")
			(hide yes)
			(effects
				(font
					(size 0.7874 0.5842)
					(thickness 0.1524)
				)
			)
		)
		(property "User Part Number" "PARTNUM*"
			(at 0.02032 4.024884 90)
			(unlocked yes)
			(layer "Cmts.User")
			(hide yes)
			(effects
				(font
					(size 0.7874 0.5842)
					(thickness 0.1524)
				)
			)
		)
		(property "Device Type" "RESISTOR-G155-133R0-01,33OHM,1%"
			(at 0.008382 1.210564 90)
			(unlocked yes)
			(layer "F.Fab")
			(hide yes)
			(effects
				(font
					(size 0.7874 0.5842)
					(thickness 0.1524)
				)
			)
		)
		(duplicate_pad_numbers_are_jumpers no)
		(fp_line
			(start 1.143 -0.5588)
			(end -1.143 -0.5588)
			(stroke
				(width 0.1)
				(type default)
			)
			(layer "F.SilkS")
		)
		(fp_line
			(start -1.143 -0.5588)
			(end -1.143 0.5588)
			(stroke
				(width 0.1)
				(type default)
			)
			(layer "F.SilkS")
		)
		(fp_line
			(start 1.143 0.5588)
			(end 1.143 -0.5588)
			(stroke
				(width 0.1)
				(type default)
			)
			(layer "F.SilkS")
		)
		(fp_line
			(start -1.143 0.5588)
			(end 1.143 0.5588)
			(stroke
				(width 0.1)
				(type default)
			)
			(layer "F.SilkS")
		)
		(fp_rect
			(start -1.143 -0.5588)
			(end 1.143 0.5588)
			(stroke
				(width 0)
				(type default)
			)
			(fill no)
			(layer "F.CrtYd")
		)
		(fp_line
			(start 0.508 -0.3048)
			(end -0.508 -0.3048)
			(stroke
				(width 0.1)
				(type default)
			)
			(layer "F.Fab")
		)
		(fp_line
			(start -0.508 -0.3048)
			(end -0.508 0.3048)
			(stroke
				(width 0.1)
				(type default)
			)
			(layer "F.Fab")
		)
		(fp_line
			(start 0.508 0.3048)
			(end 0.508 -0.3048)
			(stroke
				(width 0.1)
				(type default)
			)
			(layer "F.Fab")
		)
		(fp_line
			(start -0.508 0.3048)
			(end 0.508 0.3048)
			(stroke
				(width 0.1)
				(type default)
			)
			(layer "F.Fab")
		)
		(pad "1" smd rect
			(at -0.5334 0 90)
			(size 0.7112 0.6096)
			(layers "F.Cu" "F.Mask" "F.Paste")
			(net "SMA1_LED_GREEN_N")
		)
		(pad "2" smd rect
			(at 0.5334 0 90)
			(size 0.7112 0.6096)
			(layers "F.Cu" "F.Mask" "F.Paste")
			(net "UNNAMED_14_LED4PV14_I265_4")
		)
		(zone
			(layer "F.Cu")
			(hatch none 0.5)
			(connect_pads
				(clearance 0)
			)
			(min_thickness 0.25)
			(keepout
				(tracks not_allowed)
				(vias allowed)
				(pads allowed)
				(copperpour not_allowed)
				(footprints allowed)
			)
			(placement
				(enabled no)
				(sheetname "")
			)
			(fill
				(thermal_gap 0.5)
				(thermal_bridge_width 0.5)
				(island_removal_mode 0)
			)
			(polygon
				(pts
					(xy 10.2616 -39.242492) (xy 10.8712 -39.242492) (xy 10.8712 -39.394892) (xy 10.2616 -39.394892)
				)
			)
		)
		(zone
			(layer "F.Cu")
			(hatch none 0.5)
			(connect_pads
				(clearance 0)
			)
			(min_thickness 0.25)
			(keepout
				(tracks allowed)
				(vias not_allowed)
				(pads allowed)
				(copperpour not_allowed)
				(footprints allowed)
			)
			(placement
				(enabled no)
				(sheetname "")
			)
			(fill
				(thermal_gap 0.5)
				(thermal_bridge_width 0.5)
				(island_removal_mode 0)
			)
			(polygon
				(pts
					(xy 10.2616 -39.242492) (xy 10.8712 -39.242492) (xy 10.8712 -39.394892) (xy 10.2616 -39.394892)
				)
			)
		)
	)
	(footprint ""
		(layer "F.Cu")
		(at 79.883 -43.053)
		(property "Reference" "R96"
			(at 0 13.88237 0)
			(unlocked yes)
			(layer "F.SilkS")
			(effects
				(font
					(size 0.7874 0.5842)
					(thickness 0.1524)
				)
			)
		)
		(property "Value" "VAL*"
			(at 0.02032 2.13233 0)
			(unlocked yes)
			(layer "F.Fab")
			(hide yes)
			(effects
				(font
					(size 0.7874 0.5842)
					(thickness 0.1524)
				)
			)
		)
		(property "Device Type" "RESISTOR-G155-133R0-01,33OHM,1%"
			(at 0.008382 1.210564 0)
			(unlocked yes)
			(layer "F.Fab")
			(hide yes)
			(effects
				(font
					(size 0.7874 0.5842)
					(thickness 0.1524)
				)
			)
		)
		(property "User Part Number" "PARTNUM*"
			(at 0.02032 4.024884 0)
			(unlocked yes)
			(layer "Cmts.User")
			(hide yes)
			(effects
				(font
					(size 0.7874 0.5842)
					(thickness 0.1524)
				)
			)
		)
		(property "Tolerance" "TOL*"
			(at 0.044704 3.05435 0)
			(unlocked yes)
			(layer "Cmts.User")
			(hide yes)
			(effects
				(font
					(size 0.7874 0.5842)
					(thickness 0.1524)
				)
			)
		)
		(duplicate_pad_numbers_are_jumpers no)
		(fp_line
			(start -1.143 -0.5588)
			(end -1.143 0.5588)
			(stroke
				(width 0.1)
				(type default)
			)
			(layer "F.SilkS")
		)
		(fp_line
			(start -1.143 0.5588)
			(end 1.143 0.5588)
			(stroke
				(width 0.1)
				(type default)
			)
			(layer "F.SilkS")
		)
		(fp_line
			(start 1.143 -0.5588)
			(end -1.143 -0.5588)
			(stroke
				(width 0.1)
				(type default)
			)
			(layer "F.SilkS")
		)
		(fp_line
			(start 1.143 0.5588)
			(end 1.143 -0.5588)
			(stroke
				(width 0.1)
				(type default)
			)
			(layer "F.SilkS")
		)
		(fp_rect
			(start -1.143 0.5588)
			(end 1.143 -0.5588)
			(stroke
				(width 0)
				(type default)
			)
			(fill no)
			(layer "F.CrtYd")
		)
		(fp_line
			(start -0.508 -0.3048)
			(end -0.508 0.3048)
			(stroke
				(width 0.1)
				(type default)
			)
			(layer "F.Fab")
		)
		(fp_line
			(start -0.508 0.3048)
			(end 0.508 0.3048)
			(stroke
				(width 0.1)
				(type default)
			)
			(layer "F.Fab")
		)
		(fp_line
			(start 0.508 -0.3048)
			(end -0.508 -0.3048)
			(stroke
				(width 0.1)
				(type default)
			)
			(layer "F.Fab")
		)
		(fp_line
			(start 0.508 0.3048)
			(end 0.508 -0.3048)
			(stroke
				(width 0.1)
				(type default)
			)
			(layer "F.Fab")
		)
		(pad "1" smd rect
			(at -0.5334 0)
			(size 0.7112 0.6096)
			(layers "F.Cu" "F.Mask" "F.Paste")
			(net "MAC_ALARM")
		)
		(pad "2" smd rect
			(at 0.5334 0)
			(size 0.7112 0.6096)
			(layers "F.Cu" "F.Mask" "F.Paste")
			(net "FPGA_IN_MAC_ALARM_OUT_N")
		)
		(zone
			(layer "F.Cu")
			(hatch none 0.5)
			(connect_pads
				(clearance 0)
			)
			(min_thickness 0.25)
			(keepout
				(tracks allowed)
				(vias not_allowed)
				(pads allowed)
				(copperpour not_allowed)
				(footprints allowed)
			)
			(placement
				(enabled no)
				(sheetname "")
			)
			(fill
				(thermal_gap 0.5)
				(thermal_bridge_width 0.5)
				(island_removal_mode 0)
			)
			(polygon
				(pts
					(xy 79.8068 -42.7482) (xy 79.9592 -42.7482) (xy 79.9592 -43.3578) (xy 79.8068 -43.3578)
				)
			)
		)
	)
)
